FILE_TYPE=LIBRARY_PARTS;
primitive 'PCA9515ADGKR-1-GP';
  pin
    'NC#1':
      PIN_NUMBER='(1)';
      PIN_TYPE='ANALOG';
      NO_LOAD_CHECK='Both';
      NO_IO_CHECK='Both';
      NO_ASSERT_CHECK='TRUE';
      NO_DIR_CHECK='TRUE';
      ALLOW_CONNECT='TRUE';
    'SCL0':
      PIN_NUMBER='(2)';
      BIDIRECTIONAL='TRUE';
      INPUT_LOAD='(-0.01,0.01)';
      OUTPUT_LOAD='(1.0,-1.0)';
    'SDA0':
      PIN_NUMBER='(3)';
      BIDIRECTIONAL='TRUE';
      INPUT_LOAD='(-0.01,0.01)';
      OUTPUT_LOAD='(1.0,-1.0)';
    'GND':
      PIN_NUMBER='(4)';
      PINUSE='POWER';
      NO_LOAD_CHECK='Both';
      NO_IO_CHECK='Both';
      NO_ASSERT_CHECK='TRUE';
      NO_DIR_CHECK='TRUE';
      ALLOW_CONNECT='TRUE';
    'EN':
      PIN_NUMBER='(5)';
      INPUT_LOAD='(-0.01,0.01)';
    'SDA1':
      PIN_NUMBER='(6)';
      BIDIRECTIONAL='TRUE';
      INPUT_LOAD='(-0.01,0.01)';
      OUTPUT_LOAD='(1.0,-1.0)';
    'SCL1':
      PIN_NUMBER='(7)';
      BIDIRECTIONAL='TRUE';
      INPUT_LOAD='(-0.01,0.01)';
      OUTPUT_LOAD='(1.0,-1.0)';
    'VCC':
      PIN_NUMBER='(8)';
      PINUSE='POWER';
      NO_LOAD_CHECK='Both';
      NO_IO_CHECK='Both';
      NO_ASSERT_CHECK='TRUE';
      NO_DIR_CHECK='TRUE';
      ALLOW_CONNECT='TRUE';
  end_pin;
  body
    PART_NAME='PCA9515ADGKR-1-GP';
    BODY_NAME='PCA9515ADGKR-1-GP';
    PHYS_DES_PREFIX='U';
    CLASS='IC';
  end_body;
end_primitive;

END.
